# T6G (Grand Teton) — schematic netlist excerpt (pin names and nets, part order shuffled) for the footprints in the layout excerpt that follows; sources: Cadence DE-HDL packaged netlist, KiCad conversion of 04192023_DAF0TMB3IC0_F0TG_MB_C_brd_V02_OCP.brd

PC84  Q_CAP  22UF 4V 20% X6S  pkg C0805  page 226 : A = PVDD18_S5_P1 ; B = GND
R4124  Q_RES  100K 1% EMPTY  pkg 0402LF  page 125 : A = GPU_3V3IO_RSVD1_FFU ; B = GND
PR6612  Q_RES  0 5% CHIP  pkg 0402LF  page 362 : A = NC_P0V9_RETIMER_CPU0_IMON6 ; B = GND

(kicad_pcb
	(version 20260206)
	(generator "pcbnew")
	(generator_version "10.0")
	(general
		(thickness 1.6)
		(legacy_teardrops no)
	)
	(paper "A4")
	(title_block
		(title "04192023_DAF0TMB3IC0_F0TG_MB_C_brd_V02_OCP.brd")
		(comment 1 "Grand Teton / footprints 6621-6623 of 8354")
	)
	(layers
		(0 "F.Cu" signal "TOP")
		(4 "In1.Cu" signal "GND")
		(6 "In2.Cu" signal "IN1")
		(8 "In3.Cu" signal "GND1")
		(10 "In4.Cu" signal "IN2")
		(12 "In5.Cu" signal "GND2")
		(14 "In6.Cu" signal "IN3")
		(16 "In7.Cu" signal "GND3")
		(18 "In8.Cu" signal "VCC")
		(20 "In9.Cu" signal "VCC1")
		(22 "In10.Cu" signal "GND4")
		(24 "In11.Cu" signal "IN4")
		(26 "In12.Cu" signal "GND5")
		(28 "In13.Cu" signal "IN5")
		(30 "In14.Cu" signal "GND6")
		(32 "In15.Cu" signal "IN6")
		(34 "In16.Cu" signal "GND7")
		(2 "B.Cu" signal "BOTTOM")
		(9 "F.Adhes" user "F.Adhesive")
		(11 "B.Adhes" user "B.Adhesive")
		(13 "F.Paste" user "Package Geometry/Pastemask Top")
		(15 "B.Paste" user "Package Geometry/Pastemask Bottom")
		(5 "F.SilkS" user "Ref Des/Silkscreen Top")
		(7 "B.SilkS" user "Ref Des/Silkscreen Bottom")
		(1 "F.Mask" user "Board Geometry/Soldermask Top")
		(3 "B.Mask" user "Board Geometry/Soldermask Bottom")
		(17 "Dwgs.User" user "User.Drawings")
		(19 "Cmts.User" user "User.Comments")
		(21 "Eco1.User" user "User.Eco1")
		(23 "Eco2.User" user "User.Eco2")
		(25 "Edge.Cuts" user "Board Geometry/Outline")
		(27 "Margin" user)
		(31 "F.CrtYd" user "Package Geometry/Place Bound Top")
		(29 "B.CrtYd" user "Package Geometry/Place Bound Bottom")
		(35 "F.Fab" user "Ref Des/Assembly Top")
		(33 "B.Fab" user "Ref Des/Assembly Bottom")
	)
	(footprint ""
		(layer "B.Cu")
		(at 58.65241 -149.721824 180)
		(property "Reference" "PC84"
			(at 0 0 0)
			(layer "B.SilkS")
			(hide yes)
			(effects
				(font
					(size 1.27 1.27)
				)
				(justify mirror)
			)
		)
		(property "Value" ""
			(at 0 0 0)
			(layer "B.Fab")
			(effects
				(font
					(size 1.27 1.27)
				)
				(justify mirror)
			)
		)
		(duplicate_pad_numbers_are_jumpers no)
		(fp_line
			(start 1.524 0.762)
			(end 1.524 -0.762)
			(stroke
				(width 0.1524)
				(type default)
			)
			(layer "B.SilkS")
		)
		(fp_line
			(start 1.524 -0.762)
			(end -1.524 -0.762)
			(stroke
				(width 0.1524)
				(type default)
			)
			(layer "B.SilkS")
		)
		(fp_line
			(start -1.524 0.762)
			(end 1.524 0.762)
			(stroke
				(width 0.1524)
				(type default)
			)
			(layer "B.SilkS")
		)
		(fp_line
			(start -1.524 -0.762)
			(end -1.524 0.762)
			(stroke
				(width 0.1524)
				(type default)
			)
			(layer "B.SilkS")
		)
		(fp_line
			(start 1.1049 0.724916)
			(end -1.1049 0.724916)
			(stroke
				(width 0.1)
				(type default)
			)
			(layer "B.Fab")
		)
		(fp_line
			(start 1.1049 -0.724916)
			(end 1.1049 0.724916)
			(stroke
				(width 0.1)
				(type default)
			)
			(layer "B.Fab")
		)
		(fp_line
			(start -1.1049 0.724916)
			(end -1.1049 -0.724916)
			(stroke
				(width 0.1)
				(type default)
			)
			(layer "B.Fab")
		)
		(fp_line
			(start -1.1049 -0.724916)
			(end 1.1049 -0.724916)
			(stroke
				(width 0.1)
				(type default)
			)
			(layer "B.Fab")
		)
		(pad "1" smd rect
			(at 0.889 0 180)
			(size 1.016 1.27)
			(layers "B.Cu" "B.Mask" "B.Paste")
			(net "PVDD18_S5_P1")
		)
		(pad "2" smd rect
			(at -0.889 0 180)
			(size 1.016 1.27)
			(layers "B.Cu" "B.Mask" "B.Paste")
			(net "GND")
		)
	)
	(footprint ""
		(layer "B.Cu")
		(at 445.887602 -418.58311 90)
		(property "Reference" "PR6612"
			(at 0 0 90)
			(layer "B.SilkS")
			(hide yes)
			(effects
				(font
					(size 1.27 1.27)
				)
				(justify mirror)
			)
		)
		(property "Value" ""
			(at 0 0 90)
			(layer "B.Fab")
			(effects
				(font
					(size 1.27 1.27)
				)
				(justify mirror)
			)
		)
		(duplicate_pad_numbers_are_jumpers no)
		(fp_line
			(start 0.7874 -0.4064)
			(end -0.7874 -0.4064)
			(stroke
				(width 0.1524)
				(type default)
			)
			(layer "B.SilkS")
		)
		(fp_line
			(start -0.7874 -0.4064)
			(end -0.7874 0.4064)
			(stroke
				(width 0.1524)
				(type default)
			)
			(layer "B.SilkS")
		)
		(fp_line
			(start 0.7874 0.4064)
			(end 0.7874 -0.4064)
			(stroke
				(width 0.1524)
				(type default)
			)
			(layer "B.SilkS")
		)
		(fp_line
			(start -0.7874 0.4064)
			(end 0.7874 0.4064)
			(stroke
				(width 0.1524)
				(type default)
			)
			(layer "B.SilkS")
		)
		(fp_line
			(start 0.67945 -0.305054)
			(end 0.12065 -0.305054)
			(stroke
				(width 0.1)
				(type default)
			)
			(layer "B.Fab")
		)
		(fp_line
			(start 0.12065 -0.305054)
			(end 0.12065 -0.2794)
			(stroke
				(width 0.1)
				(type default)
			)
			(layer "B.Fab")
		)
		(fp_line
			(start -0.12065 -0.3048)
			(end -0.67945 -0.3048)
			(stroke
				(width 0.1)
				(type default)
			)
			(layer "B.Fab")
		)
		(fp_line
			(start -0.67945 -0.3048)
			(end -0.67945 0.3048)
			(stroke
				(width 0.1)
				(type default)
			)
			(layer "B.Fab")
		)
		(fp_line
			(start 0.12065 -0.2794)
			(end -0.12065 -0.2794)
			(stroke
				(width 0.1)
				(type default)
			)
			(layer "B.Fab")
		)
		(fp_line
			(start -0.12065 -0.2794)
			(end -0.12065 -0.3048)
			(stroke
				(width 0.1)
				(type default)
			)
			(layer "B.Fab")
		)
		(fp_line
			(start 0.12065 0.2794)
			(end 0.12065 0.3048)
			(stroke
				(width 0.1)
				(type default)
			)
			(layer "B.Fab")
		)
		(fp_line
			(start -0.120396 0.2794)
			(end 0.12065 0.2794)
			(stroke
				(width 0.1)
				(type default)
			)
			(layer "B.Fab")
		)
		(fp_line
			(start 0.67945 0.3048)
			(end 0.67945 -0.305054)
			(stroke
				(width 0.1)
				(type default)
			)
			(layer "B.Fab")
		)
		(fp_line
			(start 0.12065 0.3048)
			(end 0.67945 0.3048)
			(stroke
				(width 0.1)
				(type default)
			)
			(layer "B.Fab")
		)
		(fp_line
			(start -0.120396 0.3048)
			(end -0.120396 0.2794)
			(stroke
				(width 0.1)
				(type default)
			)
			(layer "B.Fab")
		)
		(fp_line
			(start -0.67945 0.3048)
			(end -0.120396 0.3048)
			(stroke
				(width 0.1)
				(type default)
			)
			(layer "B.Fab")
		)
		(pad "1" smd circle
			(at 0.40005 0 270)
			(size 0 0)
			(layers "B.Cu" "B.Mask" "B.Paste")
			(net "NC_P0V9_RETIMER_CPU0_IMON6")
		)
		(pad "2" smd circle
			(at -0.40005 0 270)
			(size 0 0)
			(layers "B.Cu" "B.Mask" "B.Paste")
			(net "GND")
		)
	)
	(footprint ""
		(layer "B.Cu")
		(at 163.387532 -430.59858 90)
		(property "Reference" "R4124"
			(at 0 0 90)
			(layer "B.SilkS")
			(hide yes)
			(effects
				(font
					(size 1.27 1.27)
				)
				(justify mirror)
			)
		)
		(property "Value" ""
			(at 0 0 90)
			(layer "B.Fab")
			(effects
				(font
					(size 1.27 1.27)
				)
				(justify mirror)
			)
		)
		(duplicate_pad_numbers_are_jumpers no)
		(fp_line
			(start 0.7874 -0.4064)
			(end -0.7874 -0.4064)
			(stroke
				(width 0.1524)
				(type default)
			)
			(layer "B.SilkS")
		)
		(fp_line
			(start -0.7874 -0.4064)
			(end -0.7874 0.4064)
			(stroke
				(width 0.1524)
				(type default)
			)
			(layer "B.SilkS")
		)
		(fp_line
			(start 0.7874 0.4064)
			(end 0.7874 -0.4064)
			(stroke
				(width 0.1524)
				(type default)
			)
			(layer "B.SilkS")
		)
		(fp_line
			(start -0.7874 0.4064)
			(end 0.7874 0.4064)
			(stroke
				(width 0.1524)
				(type default)
			)
			(layer "B.SilkS")
		)
		(fp_line
			(start 0.67945 -0.305054)
			(end 0.12065 -0.305054)
			(stroke
				(width 0.1)
				(type default)
			)
			(layer "B.Fab")
		)
		(fp_line
			(start 0.12065 -0.305054)
			(end 0.12065 -0.2794)
			(stroke
				(width 0.1)
				(type default)
			)
			(layer "B.Fab")
		)
		(fp_line
			(start -0.12065 -0.3048)
			(end -0.67945 -0.3048)
			(stroke
				(width 0.1)
				(type default)
			)
			(layer "B.Fab")
		)
		(fp_line
			(start -0.67945 -0.3048)
			(end -0.67945 0.3048)
			(stroke
				(width 0.1)
				(type default)
			)
			(layer "B.Fab")
		)
		(fp_line
			(start 0.12065 -0.2794)
			(end -0.12065 -0.2794)
			(stroke
				(width 0.1)
				(type default)
			)
			(layer "B.Fab")
		)
		(fp_line
			(start -0.12065 -0.2794)
			(end -0.12065 -0.3048)
			(stroke
				(width 0.1)
				(type default)
			)
			(layer "B.Fab")
		)
		(fp_line
			(start 0.12065 0.2794)
			(end 0.12065 0.3048)
			(stroke
				(width 0.1)
				(type default)
			)
			(layer "B.Fab")
		)
		(fp_line
			(start -0.120396 0.2794)
			(end 0.12065 0.2794)
			(stroke
				(width 0.1)
				(type default)
			)
			(layer "B.Fab")
		)
		(fp_line
			(start 0.67945 0.3048)
			(end 0.67945 -0.305054)
			(stroke
				(width 0.1)
				(type default)
			)
			(layer "B.Fab")
		)
		(fp_line
			(start 0.12065 0.3048)
			(end 0.67945 0.3048)
			(stroke
				(width 0.1)
				(type default)
			)
			(layer "B.Fab")
		)
		(fp_line
			(start -0.120396 0.3048)
			(end -0.120396 0.2794)
			(stroke
				(width 0.1)
				(type default)
			)
			(layer "B.Fab")
		)
		(fp_line
			(start -0.67945 0.3048)
			(end -0.120396 0.3048)
			(stroke
				(width 0.1)
				(type default)
			)
			(layer "B.Fab")
		)
		(pad "1" smd circle
			(at 0.40005 0 270)
			(size 0 0)
			(layers "B.Cu" "B.Mask" "B.Paste")
			(net "GPU_3V3IO_RSVD1_FFU")
		)
		(pad "2" smd circle
			(at -0.40005 0 270)
			(size 0 0)
			(layers "B.Cu" "B.Mask" "B.Paste")
			(net "GND")
		)
	)
)
